# T6G (Grand Teton) — schematic netlist excerpt (pin names and nets, part order shuffled) for the footprints in the layout excerpt that follows; sources: Cadence DE-HDL packaged netlist, KiCad conversion of 04192023_DAF0TMB3IC0_F0TG_MB_C_brd_V02_OCP.brd

H95  HOLE  EMPTY  pkg TH  page 230 : \1\ = GND
R1037  Q_RES  4.7K 5% CHIP  pkg 0201LF  page 287 : A = JTAG_TEST_MODE_RT_CPU0_P1 ; B = GND
PD115  DIODE_TVS  SMF14A IC  pkg SOD123F  page 152 : A = GND ; C = P12V_AUX

(kicad_pcb
	(version 20260206)
	(generator "pcbnew")
	(generator_version "10.0")
	(general
		(thickness 1.6)
		(legacy_teardrops no)
	)
	(paper "A4")
	(title_block
		(title "04192023_DAF0TMB3IC0_F0TG_MB_C_brd_V02_OCP.brd")
		(comment 1 "Grand Teton / footprints 1983-1985 of 8354")
	)
	(layers
		(0 "F.Cu" signal "TOP")
		(4 "In1.Cu" signal "GND")
		(6 "In2.Cu" signal "IN1")
		(8 "In3.Cu" signal "GND1")
		(10 "In4.Cu" signal "IN2")
		(12 "In5.Cu" signal "GND2")
		(14 "In6.Cu" signal "IN3")
		(16 "In7.Cu" signal "GND3")
		(18 "In8.Cu" signal "VCC")
		(20 "In9.Cu" signal "VCC1")
		(22 "In10.Cu" signal "GND4")
		(24 "In11.Cu" signal "IN4")
		(26 "In12.Cu" signal "GND5")
		(28 "In13.Cu" signal "IN5")
		(30 "In14.Cu" signal "GND6")
		(32 "In15.Cu" signal "IN6")
		(34 "In16.Cu" signal "GND7")
		(2 "B.Cu" signal "BOTTOM")
		(9 "F.Adhes" user "F.Adhesive")
		(11 "B.Adhes" user "B.Adhesive")
		(13 "F.Paste" user "Package Geometry/Pastemask Top")
		(15 "B.Paste" user "Package Geometry/Pastemask Bottom")
		(5 "F.SilkS" user "Ref Des/Silkscreen Top")
		(7 "B.SilkS" user "Ref Des/Silkscreen Bottom")
		(1 "F.Mask" user "Board Geometry/Soldermask Top")
		(3 "B.Mask" user "Board Geometry/Soldermask Bottom")
		(17 "Dwgs.User" user "User.Drawings")
		(19 "Cmts.User" user "User.Comments")
		(21 "Eco1.User" user "User.Eco1")
		(23 "Eco2.User" user "User.Eco2")
		(25 "Edge.Cuts" user "Board Geometry/Outline")
		(27 "Margin" user)
		(31 "F.CrtYd" user "Package Geometry/Place Bound Top")
		(29 "B.CrtYd" user "Package Geometry/Place Bound Bottom")
		(35 "F.Fab" user "Ref Des/Assembly Top")
		(33 "B.Fab" user "Ref Des/Assembly Bottom")
	)
	(footprint ""
		(layer "F.Cu")
		(at 335.114646 -403.603206 -90)
		(property "Reference" "R1037"
			(at 0 0 270)
			(layer "F.SilkS")
			(hide yes)
			(effects
				(font
					(size 1.27 1.27)
				)
			)
		)
		(property "Value" ""
			(at 0 0 270)
			(layer "F.Fab")
			(effects
				(font
					(size 1.27 1.27)
				)
			)
		)
		(duplicate_pad_numbers_are_jumpers no)
		(fp_line
			(start -0.32512 0.175006)
			(end -0.32512 -0.175006)
			(stroke
				(width 0.1)
				(type default)
			)
			(layer "F.Fab")
		)
		(fp_line
			(start 0.32512 0.175006)
			(end -0.32512 0.175006)
			(stroke
				(width 0.1)
				(type default)
			)
			(layer "F.Fab")
		)
		(fp_line
			(start -0.32512 -0.175006)
			(end 0.32512 -0.175006)
			(stroke
				(width 0.1)
				(type default)
			)
			(layer "F.Fab")
		)
		(fp_line
			(start 0.32512 -0.175006)
			(end 0.32512 0.175006)
			(stroke
				(width 0.1)
				(type default)
			)
			(layer "F.Fab")
		)
		(pad "1" smd rect
			(at -0.2667 0 270)
			(size 0.3048 0.381)
			(layers "F.Cu" "F.Mask" "F.Paste")
			(net "JTAG_TEST_MODE_RT_CPU0_P1")
		)
		(pad "2" smd rect
			(at 0.2667 0 90)
			(size 0.3048 0.381)
			(layers "F.Cu" "F.Mask" "F.Paste")
			(net "GND")
		)
	)
	(footprint ""
		(layer "F.Cu")
		(at 191.065404 -32.110426 180)
		(property "Reference" "PD115"
			(at 2.149348 1.672336 0)
			(unlocked yes)
			(layer "F.SilkS")
			(effects
				(font
					(size 0.7874 0.5842)
					(thickness 0.1524)
				)
				(justify left)
			)
		)
		(property "Value" ""
			(at 0 0 180)
			(layer "F.Fab")
			(effects
				(font
					(size 1.27 1.27)
				)
			)
		)
		(duplicate_pad_numbers_are_jumpers no)
		(fp_line
			(start 2.631186 0.999998)
			(end 2.631186 -0.999998)
			(stroke
				(width 0.1524)
				(type default)
			)
			(layer "F.SilkS")
		)
		(fp_line
			(start 2.631186 -0.999998)
			(end -2.250186 -0.999998)
			(stroke
				(width 0.1524)
				(type default)
			)
			(layer "F.SilkS")
		)
		(fp_line
			(start 0.381 -0.0508)
			(end 0.635 -0.0508)
			(stroke
				(width 0.1524)
				(type default)
			)
			(layer "F.SilkS")
		)
		(fp_line
			(start 0.381 -0.0508)
			(end -0.381 0.3302)
			(stroke
				(width 0.1524)
				(type default)
			)
			(layer "F.SilkS")
		)
		(fp_line
			(start 0.381 -0.4318)
			(end 0.381 0.3302)
			(stroke
				(width 0.1524)
				(type default)
			)
			(layer "F.SilkS")
		)
		(fp_line
			(start -0.381 0.3302)
			(end -0.381 -0.4318)
			(stroke
				(width 0.1524)
				(type default)
			)
			(layer "F.SilkS")
		)
		(fp_line
			(start -0.381 -0.0508)
			(end -0.6604 -0.0508)
			(stroke
				(width 0.1524)
				(type default)
			)
			(layer "F.SilkS")
		)
		(fp_line
			(start -0.381 -0.4318)
			(end 0.381 -0.0508)
			(stroke
				(width 0.1524)
				(type default)
			)
			(layer "F.SilkS")
		)
		(fp_line
			(start -2.250186 0.999998)
			(end 2.631186 0.999998)
			(stroke
				(width 0.1524)
				(type default)
			)
			(layer "F.SilkS")
		)
		(fp_line
			(start -2.250186 -0.999998)
			(end -2.250186 0.999998)
			(stroke
				(width 0.1524)
				(type default)
			)
			(layer "F.SilkS")
		)
		(fp_rect
			(start 2.6162 -0.9652)
			(end 2.1844 1.016)
			(stroke
				(width 0)
				(type default)
			)
			(fill yes)
			(layer "F.SilkS")
		)
		(fp_line
			(start 1.450086 0.999998)
			(end 1.450086 -0.999998)
			(stroke
				(width 0.1)
				(type default)
			)
			(layer "F.Fab")
		)
		(fp_line
			(start 1.450086 -0.999998)
			(end -1.450086 -0.999998)
			(stroke
				(width 0.1)
				(type default)
			)
			(layer "F.Fab")
		)
		(fp_line
			(start -1.450086 0.999998)
			(end 1.450086 0.999998)
			(stroke
				(width 0.1)
				(type default)
			)
			(layer "F.Fab")
		)
		(fp_line
			(start -1.450086 -0.999998)
			(end -1.450086 0.999998)
			(stroke
				(width 0.1)
				(type default)
			)
			(layer "F.Fab")
		)
		(fp_text user "-"
			(at 2.4384 -0.22225 180)
			(unlocked yes)
			(layer "F.SilkS")
			(effects
				(font
					(size 1.905 1.4224)
					(thickness 0.1524)
				)
				(justify left)
			)
		)
		(fp_text user "+"
			(at -3.4798 -0.22225 180)
			(unlocked yes)
			(layer "F.SilkS")
			(effects
				(font
					(size 1.905 1.4224)
					(thickness 0.1524)
				)
				(justify left)
			)
		)
		(fp_text user "-"
			(at 2.4384 -0.22225 180)
			(unlocked yes)
			(layer "F.Fab")
			(effects
				(font
					(size 1.905 1.4224)
					(thickness 0.1524)
				)
				(justify left)
			)
		)
		(fp_text user "+"
			(at -3.4798 -0.22225 180)
			(unlocked yes)
			(layer "F.Fab")
			(effects
				(font
					(size 1.905 1.4224)
					(thickness 0.1524)
				)
				(justify left)
			)
		)
		(pad "A" smd rect
			(at -1.450086 0 180)
			(size 1.3208 1.4224)
			(layers "F.Cu" "F.Mask" "F.Paste")
			(net "GND")
		)
		(pad "C" smd rect
			(at 1.450086 0 180)
			(size 1.3208 1.4224)
			(layers "F.Cu" "F.Mask" "F.Paste")
			(net "P12V_AUX")
		)
	)
	(footprint ""
		(layer "F.Cu")
		(at 461.460088 -347.699838)
		(property "Reference" "H95"
			(at -5.244084 -5.691886 0)
			(unlocked yes)
			(layer "F.SilkS")
			(effects
				(font
					(size 0.7874 0.5842)
					(thickness 0.1524)
				)
				(justify left)
			)
		)
		(property "Value" ""
			(at 0 0 0)
			(layer "F.Fab")
			(effects
				(font
					(size 1.27 1.27)
				)
			)
		)
		(duplicate_pad_numbers_are_jumpers no)
		(pad "1" thru_hole circle
			(at 0 0)
			(size 10.0076 10.0076)
			(drill 5.6134)
			(layers "*.Cu" "*.Mask")
			(remove_unused_layers no)
			(net "GND")
			(clearance -1.9431)
		)
	)
)
